FILE_TYPE = CONNECTIVITY;
{Allegro Design Entry HDL 17.4-2019 S026 (4007227) 1/17/2022}
"PAGE_NUMBER" = 297;
0"NC";
1"P3V3_E1S_0\g";
2"P3V3_E1S_0\g";
3"GND\g";
4"GND\g";
5"GND\g";
6"GND\g";
7"P3V3_E1S_0\g";
8"P3V3_AUX\g";
9"GND\g";
10"GND\g";
11"GND\g";
12"P3E_CPU0_P4_RX_DP<3:0>";
13"P3E_CPU0_P4_RX_DN<3:0>";
14"P3E_CPU0_P4_TX_C_DP<3:0>";
15"P3E_CPU0_P4_TX_C_DN<3:0>";
16"GND\g";
17"P3E_CPU0_P4_RX_DN<3>";
18"GND\g";
19"P3E_CPU0_P4_RX_DP<1>";
20"P3E_CPU0_P4_RX_DN<0>";
21"P3E_CPU0_P4_RX_DP<0>";
22"P12V_E1S_0_R\g";
23"SMB_E1S_3V3AUX_ISO_SCL";
24"SMB_E1S_3V3AUX_ISO_SDA";
25"RST_SMB_E1S_0_N";
26"FM_LED_ACTIVE_E1S_0_BUF";
27"E1S_0_PRSNT_N";
28"TP_CLK_100M_E1S_0_DP";
29"TP_CLK_100M_E1S_0_DN";
30"E1S_0_PERST1_CLKREQ_N";
31"P12V_E1S_0_R\g";
32"GND\g";
33"P3V3_E1S_0\g";
34"GND\g";
35"GND\g";
36"P3V3_AUX\g";
37"P3V3_AUX\g";
38"P3V3_E1S_0\g";
39"P3V3_E1S_0\g";
40"RST_SMB_E1S_0_N";
41"SMB_PCIE_E1S_ISO_EN";
42"PU_E1S_0_DUALPORT_EN_N";
43"TP_E1S_0_RFU";
44"RST_PCIE_E1S_PERST_N";
45"CLK_100M_CPU0_CLK12_DN";
46"CLK_100M_CPU0_CLK12_DP";
47"E1S_0_PWRDIS";
48"TP_E1S_0_MFG";
49"FM_SMB_RST_E1S_0_R_N"CDS_PHYS_NET_NAME"RST_SMB_SWITCH_N";
50"FM_LED_ACTIVE_E1S_0";
51"FM_LED_ACTIVE_E1S_0_R";
52"FM_LED_ACTIVE_E1S_0_R_BUF";
53"FM_LED_ACTIVE_E1S_0_BUF";
54"P3E_CPU0_P4_TX_C_DN<3>";
55"P3E_CPU0_P4_TX_C_DN<1>";
56"P3E_CPU0_P4_TX_C_DP<1>";
57"P3E_CPU0_P4_TX_C_DN<0>";
58"RST_PERST_E1S_0_N";
59"P3E_CPU0_P4_TX_C_DP<3>";
60"P3E_CPU0_P4_TX_C_DN<2>";
61"P3E_CPU0_P4_TX_C_DP<2>";
62"P3E_CPU0_P4_TX_C_DP<0>";
63"P3E_CPU0_P4_RX_DN<2>";
64"P3E_CPU0_P4_RX_DN<1>";
65"RST_SMB_E1S_N"CDS_PHYS_NET_NAME"RST_SMB_E1S_N";
66"RST_SMB_BUF_E1S_0_N"CDS_PHYS_NET_NAME"RST_SMB_BUF_E1S_0_N";
67"SMB_PCIE_E1S_ISO_EN_R2"CDS_PHYS_NET_NAME"SMB_PCIE_E1S_ISO_EN_R2";
68"P3E_CPU0_P4_RX_DP<3>";
69"P3E_CPU0_P4_RX_DP<2>";
70"E1S_0_PWRDIS";
%"UNIVERSAL_POWER"
"1","(-2200,975)","0","pure_quanta_power","I100";
;
HDL_POWER"P3V3_E1S_0"
CDS_LIB"pure_quanta_power"
BOM_COST"OCP3.0 ";
"A"39;
%"Q_RES"
"1","(-825,400)","0","pure_quanta","I101";
;
LOCATION"R1038"
$SEC"1"
CDS_SEC"1"
VALUE"0"
MATERIAL"CHIP"
PACK_TYPE"0402LF"
TOLERANCE"5%"
WATTAGE"1/16W"
BOM_COST"OCP3.0 "
CDS_LIB"pure_quanta"
PART_NUMBER"CS00002JB13";
"B"
$PN"2"53;
"A"
$PN"1"52;
%"Q_RES"
"2","(-700,125)","0","pure_quanta","I102";
;
LOCATION"R1000"
$SEC"1"
CDS_SEC"1"
TOLERANCE"5%"
MATERIAL"CHIP"
VALUE"4.7K"
WATTAGE"1/16W"
PACK_TYPE"0402LF"
CDS_LIB"pure_quanta"
BOM_COST"OCP3.0 "
PART_NUMBER"CS24702JB10";
"A"
$PN"1"53;
"B"
$PN"2"10;
%"UNIVERSAL_POWER"
"1","(-1775,4625)","0","pure_quanta_power","I104";
;
HDL_POWER"P3V3_E1S_0"
CDS_LIB"pure_quanta_power";
"A"1;
%"Q_RES"
"2","(2450,4475)","0","pure_quanta","I105";
;
LOCATION"R1673"
$SEC"1"
CDS_SEC"1"
VALUE"10K"
PACK_TYPE"0402LF"
WATTAGE"1/16W"
MATERIAL"CHIP"
TOLERANCE"1%"
CDS_LIB"pure_quanta"
PART_NUMBER"CS31002FB08";
"A"
$PN"1"7;
"B"
$PN"2"25;
%"Q_RES"
"2","(2925,-350)","0","pure_quanta","I106";
;
LOCATION"R3773"
$SEC"1"
CDS_SEC"1"
MATERIAL"EMPTY"
WATTAGE"1/16W"
PACK_TYPE"0402LF"
TOLERANCE"5%"
VALUE"4.7K"
CDS_LIB"pure_quanta"
PART_NUMBER"CS24702JB10";
"A"
$PN"1"36;
"B"
$PN"2"40;
%"UNIVERSAL_POWER"
"1","(2900,4800)","0","pure_quanta_power","I107";
;
HDL_POWER"P3V3_E1S_0"
CDS_LIB"pure_quanta_power";
"A"2;
%"Q_RES"
"1","(-850,-700)","0","pure_quanta","I2";
;
LOCATION"R3775"
$SEC"1"
CDS_SEC"1"
MATERIAL"CHIP"
TOLERANCE"5%"
VALUE"0"
CDS_LIB"pure_quanta"
PACK_TYPE"0402LF"
WATTAGE"1/16W"
PART_NUMBER"CS00002JB13";
"B"
$PN"2"65;
"A"
$PN"1"49;
%"UNIVERSAL_GND"
"1","(-250,2800)","0","pure_quanta_power","I20";
;
ROOM"IO_SLOT"
CDS_LIB"pure_quanta_power"
HDL_POWER"GND";
"A"18;
%"TAP"
"1","(-625,3200)","2","standard","I21";
;
CDS_LIB"standard"
BODY_TYPE"PLUMBING"
HDL_TAP"TRUE";
"B \NAC \NWC"15;
"S \NAC"
BN"3"54;
%"TAP"
"1","(-625,3300)","2","standard","I22";
;
CDS_LIB"standard"
BODY_TYPE"PLUMBING"
HDL_TAP"TRUE";
"B \NAC \NWC"15;
"S \NAC"
BN"2"60;
%"TAP"
"1","(-475,3150)","2","standard","I23";
;
CDS_LIB"standard"
BODY_TYPE"PLUMBING"
HDL_TAP"TRUE";
"B \NAC \NWC"14;
"S \NAC"
BN"3"59;
%"TAP"
"1","(-475,3350)","2","standard","I24";
;
CDS_LIB"standard"
BODY_TYPE"PLUMBING"
HDL_TAP"TRUE";
"B \NAC \NWC"14;
"S \NAC"
BN"2"61;
%"TAP"
"1","(-625,3450)","2","standard","I25";
;
CDS_LIB"standard"
BODY_TYPE"PLUMBING"
HDL_TAP"TRUE";
"B \NAC \NWC"15;
"S \NAC"
BN"1"55;
%"TAP"
"1","(-625,3600)","2","standard","I26";
;
CDS_LIB"standard"
BODY_TYPE"PLUMBING"
HDL_TAP"TRUE";
"B \NAC \NWC"15;
"S \NAC"
BN"0"57;
%"TAP"
"1","(-475,3500)","2","standard","I27";
;
CDS_LIB"standard"
BODY_TYPE"PLUMBING"
HDL_TAP"TRUE";
"B \NAC \NWC"14;
"S \NAC"
BN"1"56;
%"TAP"
"1","(-475,3650)","2","standard","I28";
;
CDS_LIB"standard"
BODY_TYPE"PLUMBING"
HDL_TAP"TRUE";
"B \NAC \NWC"14;
"S \NAC"
BN"0"62;
%"UNIVERSAL_GND"
"1","(-25,-975)","0","pure_quanta_power","I3";
;
CDS_LIB"pure_quanta_power"
HDL_POWER"GND";
"A"3;
%"Q_RES"
"1","(-1850,4050)","0","pure_quanta","I30";
;
LOCATION"R3779"
$SEC"1"
CDS_SEC"1"
VALUE"0"
MATERIAL"CHIP"
PACK_TYPE"0402LF"
WATTAGE"1/16W"
TOLERANCE"5%"
CDS_LIB"pure_quanta"
PART_NUMBER"CS00002JB13";
"B"
$PN"2"44;
"A"
$PN"1"58;
%"Q_RES"
"2","(-1775,4375)","0","pure_quanta","I31";
;
LOCATION"R2317"
$SEC"1"
CDS_SEC"1"
MATERIAL"CHIP"
VALUE"10K"
TOLERANCE"1%"
WATTAGE"1/16W"
PACK_TYPE"0402LF"
CDS_LIB"pure_quanta"
PART_NUMBER"CS31002FB08";
"A"
$PN"1"1;
"B"
$PN"2"42;
%"UNIVERSAL_POWER"
"1","(-500,4850)","0","pure_quanta_power","I33";
;
HDL_POWER"P3V3_E1S_0"
CDS_LIB"pure_quanta_power";
"A"38;
%"UNIVERSAL_POWER"
"1","(-200,5025)","0","pure_quanta_power","I34";
;
HDL_POWER"P12V_E1S_0_R"
CDS_LIB"pure_quanta_power";
"A"22;
%"UNIVERSAL_GND"
"1","(1100,-575)","0","pure_quanta_power","I35";
;
CDS_LIB"pure_quanta_power"
HDL_POWER"GND";
"A"4;
%"Q_CAP"
"1","(1100,-350)","0","pure_quanta","I36";
;
LOCATION"C1592"
$SEC"1"
CDS_SEC"1"
TOLERANCE"10%"
VOLTAGE"25V"
VALUE"0.1UF"
MATERIAL"X7R"
PACK_TYPE"0402"
CDS_LIB"pure_quanta"
PART_NUMBER"CH4104K1B00";
"B"
$PN"2"4;
"A"
$PN"1"37;
%"Q_RES"
"1","(1900,-800)","0","pure_quanta","I37";
;
LOCATION"R2114"
$SEC"1"
CDS_SEC"1"
VALUE"0"
TOLERANCE"5%"
MATERIAL"CHIP"
WATTAGE"1/16W"
PACK_TYPE"0402LF"
CDS_LIB"pure_quanta"
PART_NUMBER"CS00002JB13";
"B"
$PN"2"41;
"A"
$PN"1"67;
%"Q_RES"
"1","(1900,-700)","0","pure_quanta","I38";
;
LOCATION"R3772"
$SEC"1"
CDS_SEC"1"
PACK_TYPE"0402LF"
VALUE"0"
TOLERANCE"5%"
MATERIAL"CHIP"
WATTAGE"1/16W"
CDS_LIB"pure_quanta"
PART_NUMBER"CS00002JB13";
"B"
$PN"2"40;
"A"
$PN"1"66;
%"74LVC2G07DW7"
"1","(400,-750)","0","pure_quanta","I4";
;
LOCATION"U134"
$SEC"1"
CDS_SEC"1"
VALUE"74LVC2G07DW-7"
MATERIAL"IC"
PART_TYPE"SMLF"
CDS_LIB"pure_quanta"
CDS_LMAN_SYM_OUTLINE"-175,100,175,-100"
NEEDS_NO_SIZE"TRUE"
PART_NUMBER"AL002G07003";
"VCC"
$PN"5"37;
"GND"
$PN"2"3;
"2Y"
$PN"4"67;
"1Y"
$PN"6"66;
"2A"
$PN"3"65;
"1A"
$PN"1"65;
%"Q_RES"
"2","(3200,-350)","0","pure_quanta","I40";
;
LOCATION"R2125"
$SEC"1"
CDS_SEC"1"
TOLERANCE"5%"
MATERIAL"CHIP"
VALUE"4.7K"
PACK_TYPE"0402LF"
WATTAGE"1/16W"
CDS_LIB"pure_quanta"
PART_NUMBER"CS24702JB10";
"A"
$PN"1"36;
"B"
$PN"2"41;
%"UNIVERSAL_POWER"
"1","(1100,-25)","0","pure_quanta_power","I43";
;
HDL_POWER"P3V3_AUX"
CDS_LIB"pure_quanta_power";
"A"37;
%"UNIVERSAL_GND"
"1","(-2900,1900)","0","pure_quanta_power","I5";
;
CDS_LIB"pure_quanta_power"
HDL_POWER"GND";
"A"5;
%"UNIVERSAL_GND"
"1","(1550,2800)","0","pure_quanta_power","I52";
;
ROOM"IO_SLOT"
CDS_LIB"pure_quanta_power"
HDL_POWER"GND";
"A"16;
%"TAP"
"1","(1975,3150)","0","standard","I54";
;
CDS_LIB"standard"
BODY_TYPE"PLUMBING"
HDL_TAP"TRUE";
"B \NAC \NWC"13;
"S \NAC"
BN"3"17;
%"TAP"
"1","(1825,3350)","0","standard","I55";
;
CDS_LIB"standard"
BODY_TYPE"PLUMBING"
HDL_TAP"TRUE";
"B \NAC \NWC"12;
"S \NAC"
BN"2"69;
%"TAP"
"1","(1825,3200)","0","standard","I56";
;
CDS_LIB"standard"
BODY_TYPE"PLUMBING"
HDL_TAP"TRUE";
"B \NAC \NWC"12;
"S \NAC"
BN"3"68;
%"TAP"
"1","(1975,3300)","0","standard","I57";
;
CDS_LIB"standard"
BODY_TYPE"PLUMBING"
HDL_TAP"TRUE";
"B \NAC \NWC"13;
"S \NAC"
BN"2"63;
%"TAP"
"1","(1825,3500)","0","standard","I58";
;
CDS_LIB"standard"
BODY_TYPE"PLUMBING"
HDL_TAP"TRUE";
"B \NAC \NWC"12;
"S \NAC"
BN"1"19;
%"TAP"
"1","(1825,3650)","0","standard","I59";
;
CDS_LIB"standard"
BODY_TYPE"PLUMBING"
HDL_TAP"TRUE";
"B \NAC \NWC"12;
"S \NAC"
BN"0"21;
%"Q_RES"
"2","(-2900,2150)","0","pure_quanta","I6";
;
LOCATION"R10296"
$SEC"1"
CDS_SEC"1"
TOLERANCE"1%"
PACK_TYPE"0402LF"
WATTAGE"1/16W"
MATERIAL"CHIP"
VALUE"1K"
CDS_LIB"pure_quanta"
PART_NUMBER"CS21002FB06";
"A"
$PN"1"70;
"B"
$PN"2"5;
%"TAP"
"1","(1975,3450)","0","standard","I60";
;
CDS_LIB"standard"
BODY_TYPE"PLUMBING"
HDL_TAP"TRUE";
"B \NAC \NWC"13;
"S \NAC"
BN"1"64;
%"TAP"
"1","(1975,3600)","0","standard","I61";
;
CDS_LIB"standard"
BODY_TYPE"PLUMBING"
HDL_TAP"TRUE";
"B \NAC \NWC"13;
"S \NAC"
BN"0"20;
%"UNIVERSAL_POWER"
"1","(2925,0)","0","pure_quanta_power","I64";
;
HDL_POWER"P3V3_AUX"
CDS_LIB"pure_quanta_power";
"A"36;
%"Q_CAP"
"1","(2475,2675)","0","pure_quanta","I66";
;
LOCATION"C1276"
$SEC"1"
CDS_SEC"1"
VALUE"22UF"
VOLTAGE"16V"
MATERIAL"X6S"
PACK_TYPE"C0805"
TOLERANCE"20%"
CDS_LIB"pure_quanta"
PART_NUMBER"CH6223MEA01";
"B"
$PN"2"35;
"A"
$PN"1"31;
%"Q_CAP"
"1","(2750,2675)","0","pure_quanta","I67";
;
LOCATION"C1277"
$SEC"1"
CDS_SEC"1"
VOLTAGE"16V"
PACK_TYPE"C0805"
MATERIAL"X6S"
TOLERANCE"20%"
VALUE"22UF"
CDS_LIB"pure_quanta"
PART_NUMBER"CH6223MEA01";
"B"
$PN"2"35;
"A"
$PN"1"31;
%"Q_CAP"
"1","(3150,2675)","0","pure_quanta","I68";
;
LOCATION"C1278"
$SEC"1"
CDS_SEC"1"
MATERIAL"X7R"
TOLERANCE"10%"
VALUE"0.1UF"
VOLTAGE"25V"
PACK_TYPE"0402"
CDS_LIB"pure_quanta"
PART_NUMBER"CH4104K1B00";
"B"
$PN"2"35;
"A"
$PN"1"31;
%"UNIVERSAL_POWER"
"1","(2475,3025)","0","pure_quanta_power","I69";
;
HDL_POWER"P12V_E1S_0_R"
CDS_LIB"pure_quanta_power";
"A"31;
%"Q_RES"
"2","(-2900,2650)","0","pure_quanta","I7";
;
LOCATION"R3771"
$SEC"1"
CDS_SEC"1"
VALUE"10K"
PACK_TYPE"0402LF"
MATERIAL"CHIP"
WATTAGE"1/16W"
TOLERANCE"1%"
CDS_LIB"pure_quanta"
PART_NUMBER"CS31002FB08";
"A"
$PN"1"8;
"B"
$PN"2"70;
%"UNIVERSAL_GND"
"1","(3425,2325)","0","pure_quanta_power","I73";
;
ROOM"IO_SLOT"
CDS_LIB"pure_quanta_power"
HDL_POWER"GND";
"A"35;
%"Q_CAP"
"1","(3425,2675)","0","pure_quanta","I74";
;
LOCATION"C1279"
$SEC"1"
CDS_SEC"1"
PACK_TYPE"0402"
VALUE"0.1UF"
VOLTAGE"25V"
MATERIAL"X7R"
TOLERANCE"10%"
CDS_LIB"pure_quanta"
PART_NUMBER"CH4104K1B00";
"B"
$PN"2"35;
"A"
$PN"1"31;
%"Q_RES"
"2","(4000,3700)","0","pure_quanta","I75";
;
LOCATION"R2426"
$SEC"1"
CDS_SEC"1"
TOLERANCE"1%"
WATTAGE"1/16W"
MATERIAL"EMPTY"
PACK_TYPE"0402LF"
VALUE"100"
CDS_LIB"pure_quanta"
PART_NUMBER"CS11002FB07";
"A"
$PN"1"30;
"B"
$PN"2"6;
%"UNIVERSAL_GND"
"1","(4000,3475)","0","pure_quanta_power","I76";
;
ROOM"IO_SLOT"
CDS_LIB"pure_quanta_power"
HDL_POWER"GND";
"A"6;
%"UNIVERSAL_POWER"
"1","(2450,4675)","0","pure_quanta_power","I78";
;
HDL_POWER"P3V3_E1S_0"
CDS_LIB"pure_quanta_power";
"A"7;
%"Q_RES"
"2","(2900,4475)","0","pure_quanta","I79";
;
LOCATION"R10287"
$SEC"1"
CDS_SEC"1"
TOLERANCE"1%"
VALUE"10K"
MATERIAL"CHIP"
PACK_TYPE"0402LF"
WATTAGE"1/16W"
CDS_LIB"pure_quanta"
PART_NUMBER"CS31002FB08";
"A"
$PN"1"2;
"B"
$PN"2"30;
%"UNIVERSAL_POWER"
"1","(-2900,2900)","0","pure_quanta_power","I8";
;
HDL_POWER"P3V3_AUX"
CDS_LIB"pure_quanta_power";
"A"8;
%"UNIVERSAL_GND"
"1","(4750,2325)","0","pure_quanta_power","I86";
;
ROOM"IO_SLOT"
CDS_LIB"pure_quanta_power"
HDL_POWER"GND";
"A"34;
%"Q_CAP"
"1","(4500,2675)","0","pure_quanta","I87";
;
LOCATION"C1282"
$SEC"1"
CDS_SEC"1"
VOLTAGE"25V"
VALUE"0.1UF"
PACK_TYPE"0402"
MATERIAL"X7R"
TOLERANCE"10%"
CDS_LIB"pure_quanta"
PART_NUMBER"CH4104K1B00";
"B"
$PN"2"34;
"A"
$PN"1"33;
%"Q_CAP"
"1","(4750,2675)","0","pure_quanta","I88";
;
LOCATION"C1283"
$SEC"1"
CDS_SEC"1"
VALUE"0.1UF"
VOLTAGE"25V"
MATERIAL"X7R"
PACK_TYPE"0402"
TOLERANCE"10%"
CDS_LIB"pure_quanta"
PART_NUMBER"CH4104K1B00";
"B"
$PN"2"34;
"A"
$PN"1"33;
%"UNIVERSAL_POWER"
"1","(4500,3025)","0","pure_quanta_power","I89";
;
HDL_POWER"P3V3_E1S_0"
CDS_LIB"pure_quanta_power";
"A"33;
%"SCONN56_123276793"
"1","(650,3725)","0","pure_quanta","I90";
;
LOCATION"J90"
$SEC"1"
CDS_SEC"1"
PART_TYPE"SMLF"
VALUE"SCONN56_1-2327679-3"
MATERIAL"IO"
CDS_LMAN_SYM_OUTLINE"-575,875,575,-875"
NEEDS_NO_SIZE"TRUE"
CDS_LIB"pure_quanta"
PART_NUMBER"DFHS56FS022";
"G1"
$PN"G1"16;
"G2"
$PN"G2"18;
"PER_P3"
$PN"A27"17;
"PER_N3"
$PN"A26"68;
"PER_P2"
$PN"A24"63;
"PER_N2"
$PN"A23"69;
"PER_P1"
$PN"A21"64;
"PER_N1"
$PN"A20"19;
"PER_P0"
$PN"A18"20;
"PER_N0"
$PN"A17"21;
"REFCLK_P1"
$PN"A15"28;
"REFCLK_N1"
$PN"A14"29;
"GND_A28"
$PN"A28"16;
"GND_A25"
$PN"A25"16;
"GND_A22"
$PN"A22"16;
"GND_A19"
$PN"A19"16;
"GND_A16"
$PN"A16"16;
"GND_A13"
$PN"A13"16;
"PRSNT0# \B"
$PN"A12"27;
"PERST1#_CLKREQ# \B"
$PN"A11"30;
"PERST0# \B"
$PN"B10"44;
"LED#_ACTIVITY"
$PN"A10"26;
"SMBRST# \B"
$PN"A9"25;
"SMBDAT"
$PN"A8"24;
"SMBCLK"
$PN"A7"23;
"PET_P3"
$PN"B27"59;
"PET_N3"
$PN"B26"54;
"PET_P2"
$PN"B24"60;
"PET_N2"
$PN"B23"61;
"PET_P1"
$PN"B21"55;
"PET_N1"
$PN"B20"56;
"PET_P0"
$PN"B18"57;
"PET_N0"
$PN"B17"62;
"REFCLK_P0"
$PN"B15"46;
"REFCLK_N0"
$PN"B14"45;
"GND_B28"
$PN"B28"18;
"GND_B25"
$PN"B25"18;
"GND_B22"
$PN"B22"18;
"GND_B19"
$PN"B19"18;
"GND_B16"
$PN"B16"18;
"GND_B13"
$PN"B13"18;
"PWRDIS"
$PN"B12"47;
"P3V3_AUX"
$PN"B11"38;
"DUALPORTEN# \B"
$PN"B9"42;
"RFU"
$PN"B8"43;
"MFG"
$PN"B7"48;
"GND_A6"
$PN"A6"16;
"GND_A5"
$PN"A5"16;
"GND_A4"
$PN"A4"16;
"GND_A3"
$PN"A3"16;
"GND_A2"
$PN"A2"16;
"GND_A1"
$PN"A1"16;
"P12V_B6"
$PN"B6"22;
"P12V_B5"
$PN"B5"22;
"P12V_B4"
$PN"B4"22;
"P12V_B3"
$PN"B3"22;
"P12V_B2"
$PN"B2"22;
"P12V_B1"
$PN"B1"22;
%"UNIVERSAL_GND"
"1","(-2875,-100)","2","pure_quanta_power","I91";
;
CDS_LIB"pure_quanta_power"
HDL_POWER"GND";
"A"9;
%"UNIVERSAL_GND"
"1","(-700,-100)","2","pure_quanta_power","I92";
;
CDS_LIB"pure_quanta_power"
HDL_POWER"GND";
"A"10;
%"Q_RES"
"1","(-3125,400)","0","pure_quanta","I94";
;
LOCATION"R955"
$SEC"1"
CDS_SEC"1"
VALUE"0"
MATERIAL"CHIP"
PACK_TYPE"0402LF"
TOLERANCE"5%"
WATTAGE"1/16W"
CDS_LIB"pure_quanta"
BOM_COST"OCP3.0 "
PART_NUMBER"CS00002JB13";
"B"
$PN"2"51;
"A"
$PN"1"50;
%"Q_RES"
"2","(-2875,125)","0","pure_quanta","I95";
;
LOCATION"R999"
$SEC"1"
CDS_SEC"1"
TOLERANCE"5%"
WATTAGE"1/16W"
PACK_TYPE"0402LF"
VALUE"4.7K"
MATERIAL"CHIP"
BOM_COST"OCP3.0 "
CDS_LIB"pure_quanta"
PART_NUMBER"CS24702JB10";
"A"
$PN"1"51;
"B"
$PN"2"9;
%"UNIVERSAL_GND"
"1","(-2125,200)","2","pure_quanta_power","I96";
;
CDS_LIB"pure_quanta_power"
HDL_POWER"GND";
"A"32;
%"74LVC1G17GW"
"1","(-1925,400)","0","pure_quanta","I97";
;
LOCATION"U44"
$SEC"1"
CDS_SEC"1"
VALUE"74LVC1G17GW"
MATERIAL"IC"
PART_TYPE"SMLF"
CDS_LIB"pure_quanta"
PIN_NAMES_ROTATE"True"
CDS_LMAN_SYM_OUTLINE"-125,150,125,-150"
PART_NUMBER"AL1G0017K01";
"NC"
$PN"1"0;
"Y"
$PN"4"52;
"GND"
$PN"3"32;
"A"
$PN"2"51;
"VCC"
$PN"5"39;
%"UNIVERSAL_GND"
"1","(-2275,500)","2","pure_quanta_power","I98";
;
CDS_LIB"pure_quanta_power"
HDL_POWER"GND";
"A"11;
%"Q_CAP"
"1","(-2275,700)","2","pure_quanta","I99";
;
LOCATION"C508"
$SEC"1"
CDS_SEC"1"
TOLERANCE"10%"
VOLTAGE"25V"
MATERIAL"X7R"
VALUE"0.1UF"
PACK_TYPE"0402"
CDS_LIB"pure_quanta"
PART_NUMBER"CH4104K1B00";
"B"
$PN"2"11;
"A"
$PN"1"39;
END.
